#ISCELL
  mstr_misc dns *
  *
#ISCELL
  pure_quanta quanta_title_block_c *
  *
#ISCELL
  standard offpage *
  page170_i1
#ISCELL
  standard offpage *
  page170_i10
#CELL
  pure_quanta q_res *
  page170_i11
#CELL
  pure_quanta q_res *
  page170_i12
#ISCELL
  pure_quanta_power vcc_core *
  page170_i13
#ISCELL
  pure_quanta_power universal_gnd *
  page170_i14
#CELL
  pure_quanta q_cap *
  page170_i15
#ISCELL
  pure_quanta_power universal_gnd *
  page170_i16
#ISCELL
  pure_quanta_power universal_gnd *
  page170_i17
#CELL
  pure_quanta q_res *
  page170_i18
#CELL
  pure_quanta q_cap *
  page170_i19
#CELL
  pure_quanta q_cap *
  page170_i2
#CELL
  pure_quanta q_res *
  page170_i20
#CELL
  pure_quanta q_cap *
  page170_i21
#CELL
  pure_quanta q_cap *
  page170_i22
#CELL
  pure_quanta q_cap *
  page170_i23
#CELL
  pure_quanta q_cap *
  page170_i24
#ISCELL
  pure_quanta_power universal_gnd *
  page170_i25
#CELL
  pure_quanta q_res *
  page170_i26
#CELL
  pure_quanta q_cap *
  page170_i27
#ISCELL
  pure_quanta_power universal_gnd *
  page170_i28
#ISCELL
  standard offpage *
  page170_i29
#ISCELL
  pure_quanta_power universal_gnd *
  page170_i3
#ISCELL
  pure_quanta_power universal_gnd *
  page170_i30
#ISCELL
  standard offpage *
  page170_i31
#ISCELL
  standard offpage *
  page170_i32
#CELL
  pure_quanta q_res *
  page170_i33
#ISCELL
  pure_quanta_power universal_gnd *
  page170_i34
#ISCELL
  standard offpage *
  page170_i35
#CELL
  pure_quanta q_cap *
  page170_i36
#CELL
  pure_quanta q_res *
  page170_i37
#CELL
  pure_quanta isl99390frztr5935 *
  page170_i38
#ISCELL
  pure_quanta_power universal_gnd *
  page170_i39
#ISCELL
  pure_quanta_power universal_gnd *
  page170_i4
#CELL
  pure_quanta q_cap *
  page170_i40
#ISCELL
  pure_quanta_power vcc_core *
  page170_i41
#ISCELL
  pure_quanta_power universal_gnd *
  page170_i42
#CELL
  pure_quanta q_cap *
  page170_i43
#CELL
  pure_quanta q_res *
  page170_i44
#CELL
  pure_quanta q_cap *
  page170_i45
#CELL
  pure_quanta q_res *
  page170_i46
#CELL
  pure_quanta q_cap *
  page170_i47
#CELL
  pure_quanta q_cap *
  page170_i48
#CELL
  pure_quanta q_cap *
  page170_i49
#ISCELL
  pure_quanta_power universal_gnd *
  page170_i5
#CELL
  pure_quanta q_res *
  page170_i50
#ISCELL
  standard offpage *
  page170_i51
#CELL
  pure_quanta q_inductor4p_14 *
  page170_i52
#CELL
  pure_quanta q_cap *
  page170_i53
#ISCELL
  pure_quanta_power universal_gnd *
  page170_i54
#CELL
  pure_quanta q_cap *
  page170_i55
#ISCELL
  pure_quanta_power vcc_core *
  page170_i56
#ISCELL
  pure_quanta_power universal_gnd *
  page170_i57
#CELL
  pure_quanta q_cap *
  page170_i58
#ISCELL
  pure_quanta_power universal_gnd *
  page170_i59
#CELL
  pure_quanta q_cap *
  page170_i6
#CELL
  pure_quanta q_cap *
  page170_i60
#ISCELL
  pure_quanta_power vcc_core *
  page170_i61
#ISCELL
  standard offpage *
  page170_i62
#CELL
  pure_quanta q_cap *
  page170_i63
#CELL
  pure_quanta q_inductor4p_14 *
  page170_i64
#ISCELL
  pure_quanta_power universal_gnd *
  page170_i65
#CELL
  pure_quanta q_cap *
  page170_i66
#ISCELL
  pure_quanta_power vcc_core *
  page170_i67
#ISCELL
  standard offpage *
  page170_i68
#ISCELL
  pure_quanta_power universal_gnd *
  page170_i69
#ISCELL
  standard offpage *
  page170_i7
#CELL
  pure_quanta q_cap *
  page170_i70
#CELL
  pure_quanta q_cap *
  page170_i71
#ISCELL
  pure_quanta_power vcc_core *
  page170_i72
#ISCELL
  standard offpage *
  page170_i8
#CELL
  pure_quanta isl99390frztr5935 *
  page170_i9
